# T6G (Grand Teton) — schematic netlist excerpt (pin names and nets, part order shuffled) for the footprints in the layout excerpt that follows; sources: Cadence DE-HDL packaged netlist, KiCad conversion of 04192023_DAF0TMB3IC0_F0TG_MB_C_brd_V02_OCP.brd

J112  CONN160_10131762101LF  CONN160_10131762-101LF IO  pkg HSD_F160D8_P2W1-2_RDH  page 122
  A1  = RST_PERST_2_SWB_BUF_N
  A2  = GND
  A3  = HGX_DETECT_N_ISO
  A4  = GND
  A5  = RST_PERST_1_SWB_BUF_N
  A6  = GND
  A7  = PRSNT_SWB_N
  A8  = GND
  B1  = GND
  B2  = P5E_CPU1_P0_RX_BUF_DN<1>
  B3  = GND
  B4  = P5E_CPU1_P0_RX_BUF_DN<3>
  B5  = GND
  B6  = P5E_CPU1_P0_RX_BUF_DN<5>
  B7  = GND
  B8  = P5E_CPU1_P0_RX_BUF_DN<7>
  C1  = P5E_CPU1_P0_RX_BUF_DN<0>
  C2  = P5E_CPU1_P0_RX_BUF_DP<1>
  C3  = P5E_CPU1_P0_RX_BUF_DN<2>
  C4  = P5E_CPU1_P0_RX_BUF_DP<3>
  C5  = P5E_CPU1_P0_RX_BUF_DN<4>
  C6  = P5E_CPU1_P0_RX_BUF_DP<5>
  C7  = P5E_CPU1_P0_RX_BUF_DN<6>
  C8  = P5E_CPU1_P0_RX_BUF_DP<7>
  D1  = P5E_CPU1_P0_RX_BUF_DP<0>
  D2  = GND
  D3  = P5E_CPU1_P0_RX_BUF_DP<2>
  D4  = GND
  D5  = P5E_CPU1_P0_RX_BUF_DP<4>
  D6  = GND
  D7  = P5E_CPU1_P0_RX_BUF_DP<6>
  D8  = GND
  E1  = GND
  E2  = P5E_CPU1_P1_RX_BUF_DN<1>
  E3  = GND
  E4  = P5E_CPU1_P1_RX_BUF_DN<3>
  E5  = GND
  E6  = P5E_CPU1_P1_RX_BUF_DN<5>
  E7  = GND
  E8  = P5E_CPU1_P1_RX_BUF_DN<7>
  F1  = P5E_CPU1_P1_RX_BUF_DN<0>
  F2  = P5E_CPU1_P1_RX_BUF_DP<1>
  F3  = P5E_CPU1_P1_RX_BUF_DN<2>
  F4  = P5E_CPU1_P1_RX_BUF_DP<3>
  F5  = P5E_CPU1_P1_RX_BUF_DN<4>
  F6  = P5E_CPU1_P1_RX_BUF_DP<5>
  F7  = P5E_CPU1_P1_RX_BUF_DN<6>
  F8  = P5E_CPU1_P1_RX_BUF_DP<7>
  G1  = P5E_CPU1_P1_RX_BUF_DP<0>
  G2  = GND
  G3  = P5E_CPU1_P1_RX_BUF_DP<2>
  G4  = GND
  G5  = P5E_CPU1_P1_RX_BUF_DP<4>
  G6  = GND
  G7  = P5E_CPU1_P1_RX_BUF_DP<6>
  G8  = GND
  H1  = GND
  H2  = P5E_CPU1_P0_TX_BUF_C_DN<1>
  H3  = GND
  H4  = P5E_CPU1_P0_TX_BUF_C_DN<3>
  H5  = GND
  H6  = P5E_CPU1_P0_TX_BUF_C_DN<5>
  H7  = GND
  H8  = P5E_CPU1_P0_TX_BUF_C_DN<7>
  I1  = P5E_CPU1_P0_TX_BUF_C_DN<0>
  I2  = P5E_CPU1_P0_TX_BUF_C_DP<1>
  I3  = P5E_CPU1_P0_TX_BUF_C_DN<2>
  I4  = P5E_CPU1_P0_TX_BUF_C_DP<3>
  I5  = P5E_CPU1_P0_TX_BUF_C_DN<4>
  I6  = P5E_CPU1_P0_TX_BUF_C_DP<5>
  I7  = P5E_CPU1_P0_TX_BUF_C_DN<6>
  I8  = P5E_CPU1_P0_TX_BUF_C_DP<7>
  J1  = P5E_CPU1_P0_TX_BUF_C_DP<0>
  J2  = GND
  J3  = P5E_CPU1_P0_TX_BUF_C_DP<2>
  J4  = GND
  J5  = P5E_CPU1_P0_TX_BUF_C_DP<4>
  J6  = GND
  J7  = P5E_CPU1_P0_TX_BUF_C_DP<6>
  J8  = GND
  K1  = GND
  K2  = P5E_CPU1_P1_TX_BUF_C_DN<1>
  K3  = GND
  K4  = P5E_CPU1_P1_TX_BUF_C_DN<3>
  K5  = GND
  K6  = P5E_CPU1_P1_TX_BUF_C_DN<5>
  K7  = GND
  K8  = P5E_CPU1_P1_TX_BUF_C_DN<7>
  L1  = P5E_CPU1_P1_TX_BUF_C_DN<0>
  L2  = P5E_CPU1_P1_TX_BUF_C_DP<1>
  L3  = P5E_CPU1_P1_TX_BUF_C_DN<2>
  L4  = P5E_CPU1_P1_TX_BUF_C_DP<3>
  L5  = P5E_CPU1_P1_TX_BUF_C_DN<4>
  L6  = P5E_CPU1_P1_TX_BUF_C_DP<5>
  L7  = P5E_CPU1_P1_TX_BUF_C_DN<6>
  L8  = P5E_CPU1_P1_TX_BUF_C_DP<7>
  M1  = P5E_CPU1_P1_TX_BUF_C_DP<0>
  M2  = GND
  M3  = P5E_CPU1_P1_TX_BUF_C_DP<2>
  M4  = GND
  M5  = P5E_CPU1_P1_TX_BUF_C_DP<4>
  M6  = GND
  M7  = P5E_CPU1_P1_TX_BUF_C_DP<6>
  M8  = GND
  N1  = GND
  N2  = NC_J112_N2
  N3  = GND
  N4  = CLK_100M_CPU0_CLK11_DN
  N5  = GND
  N6  = P2E_MB_BMC_RX_DP<0>
  N7  = GND
  N8  = P3E_CPU1_P5_RX_DN<0>
  O1  = CLK_100M_CPU1_CLK01_DN
  O2  = NC_J112_O2
  O3  = CLK_100M_CPU1_CLK11_DN
  O4  = CLK_100M_CPU0_CLK11_DP
  O5  = NC_J112_O5
  O6  = P2E_MB_BMC_RX_DN<0>
  O7  = P3E_CPU1_P5_RX_DN<1>
  O8  = P3E_CPU1_P5_RX_DP<0>
  P1  = CLK_100M_CPU1_CLK01_DP
  P2  = GND
  P3  = CLK_100M_CPU1_CLK11_DP
  P4  = GND
  P5  = NC_J112_P5
  P6  = GND
  P7  = P3E_CPU1_P5_RX_DP<1>
  P8  = GND
  Q1  = GND
  Q2  = CLK_100M_GPU_FPGA_DN
  Q3  = GND
  Q4  = SMB_1_BMC_GPU_BUF_SCL
  Q5  = GND
  Q6  = P2E_MB_BMC_TX_BUF_C_DP<0>
  Q7  = GND
  Q8  = P3E_CPU1_P5_TX_C_DN<0>
  R1  = USB2_HUB_BUF_SWB_DN
  R2  = CLK_100M_GPU_FPGA_DP
  R3  = SMB_2_BMC_GPU_BUF_SCL
  R4  = SMB_1_BMC_GPU_BUF_SDA
  R5  = NC_J112_R5
  R6  = P2E_MB_BMC_TX_BUF_C_DN<0>
  R7  = P3E_CPU1_P5_TX_C_DP<1>
  R8  = P3E_CPU1_P5_TX_C_DP<0>
  S1  = USB2_HUB_BUF_SWB_DP
  S2  = GND
  S3  = SMB_2_BMC_GPU_BUF_SDA
  S4  = GND
  S5  = NC_J112_S5
  S6  = GND
  S7  = P3E_CPU1_P5_TX_C_DN<1>
  S8  = GND
  T1  = GND
  T2  = GPU_FPGA_READY
  T3  = GND
  T4  = GPU_NVS_PWR_BRAKE_N_BUF
  T5  = GND
  T6  = GPU_FPGA_THERM_OVERT_N
  T7  = GND
  T8  = RST_PERST_0_SWB_BUF_N

(kicad_pcb
	(version 20260206)
	(generator "pcbnew")
	(generator_version "10.0")
	(general
		(thickness 1.6)
		(legacy_teardrops no)
	)
	(paper "A4")
	(title_block
		(title "04192023_DAF0TMB3IC0_F0TG_MB_C_brd_V02_OCP.brd")
		(comment 1 "Grand Teton / footprint 625 of 8354 (J112), pads 1-31 of 74")
	)
	(layers
		(0 "F.Cu" signal "TOP")
		(4 "In1.Cu" signal "GND")
		(6 "In2.Cu" signal "IN1")
		(8 "In3.Cu" signal "GND1")
		(10 "In4.Cu" signal "IN2")
		(12 "In5.Cu" signal "GND2")
		(14 "In6.Cu" signal "IN3")
		(16 "In7.Cu" signal "GND3")
		(18 "In8.Cu" signal "VCC")
		(20 "In9.Cu" signal "VCC1")
		(22 "In10.Cu" signal "GND4")
		(24 "In11.Cu" signal "IN4")
		(26 "In12.Cu" signal "GND5")
		(28 "In13.Cu" signal "IN5")
		(30 "In14.Cu" signal "GND6")
		(32 "In15.Cu" signal "IN6")
		(34 "In16.Cu" signal "GND7")
		(2 "B.Cu" signal "BOTTOM")
		(9 "F.Adhes" user "F.Adhesive")
		(11 "B.Adhes" user "B.Adhesive")
		(13 "F.Paste" user "Package Geometry/Pastemask Top")
		(15 "B.Paste" user "Package Geometry/Pastemask Bottom")
		(5 "F.SilkS" user "Ref Des/Silkscreen Top")
		(7 "B.SilkS" user "Ref Des/Silkscreen Bottom")
		(1 "F.Mask" user "Board Geometry/Soldermask Top")
		(3 "B.Mask" user "Board Geometry/Soldermask Bottom")
		(17 "Dwgs.User" user "User.Drawings")
		(19 "Cmts.User" user "User.Comments")
		(21 "Eco1.User" user "User.Eco1")
		(23 "Eco2.User" user "User.Eco2")
		(25 "Edge.Cuts" user "Board Geometry/Outline")
		(27 "Margin" user)
		(31 "F.CrtYd" user "Package Geometry/Place Bound Top")
		(29 "B.CrtYd" user "Package Geometry/Place Bound Bottom")
		(35 "F.Fab" user "Ref Des/Assembly Top")
		(33 "B.Fab" user "Ref Des/Assembly Bottom")
	)
	(footprint ""
		(layer "F.Cu")
		(at 58.64987 -440.489848)
		(property "Reference" "J112"
			(at -4.958842 26.716736 90)
			(unlocked yes)
			(layer "F.SilkS")
			(effects
				(font
					(size 0.7874 0.5842)
					(thickness 0.1524)
				)
				(justify left)
			)
		)
		(property "Value" ""
			(at 0 0 0)
			(layer "F.Fab")
			(effects
				(font
					(size 1.27 1.27)
				)
			)
		)
		(duplicate_pad_numbers_are_jumpers no)
		(pad "A1" thru_hole rect
			(at 0 0 180)
			(size 0.766318 0.766318)
			(drill 0.359918)
			(layers "*.Cu" "*.Mask")
			(remove_unused_layers no)
			(net "RST_PERST_2_SWB_BUF_N")
			(clearance 0.0508)
			(thermal_gap 0.0508)
			(padstack
				(mode front_inner_back)
				(layer "Inner"
					(shape circle)
					(size 0.766318 0.766318)
					(clearance 0.0508)
				)
				(layer "B.Cu"
					(shape rect)
					(size 0.766318 0.766318)
					(clearance 0.0508)
				)
			)
		)
		(pad "A2" thru_hole circle
			(at 1.999996 0.199898 180)
			(size 0.906272 0.906272)
			(drill 0.499872)
			(layers "*.Cu" "*.Mask")
			(remove_unused_layers no)
			(net "GND")
			(clearance 0.0508)
			(thermal_gap 0.0508)
		)
		(pad "A3" thru_hole circle
			(at 3.999992 0 180)
			(size 0.766318 0.766318)
			(drill 0.359918)
			(layers "*.Cu" "*.Mask")
			(remove_unused_layers no)
			(net "HGX_DETECT_N_ISO")
			(clearance 0.0508)
			(thermal_gap 0.0508)
		)
		(pad "A4" thru_hole circle
			(at 5.999988 0.199898 180)
			(size 0.906272 0.906272)
			(drill 0.499872)
			(layers "*.Cu" "*.Mask")
			(remove_unused_layers no)
			(net "GND")
			(clearance 0.0508)
			(thermal_gap 0.0508)
		)
		(pad "A5" thru_hole circle
			(at 7.999984 0 180)
			(size 0.766318 0.766318)
			(drill 0.359918)
			(layers "*.Cu" "*.Mask")
			(remove_unused_layers no)
			(net "RST_PERST_1_SWB_BUF_N")
			(clearance 0.0508)
			(thermal_gap 0.0508)
		)
		(pad "A6" thru_hole circle
			(at 9.99998 0.199898 180)
			(size 0.906272 0.906272)
			(drill 0.499872)
			(layers "*.Cu" "*.Mask")
			(remove_unused_layers no)
			(net "GND")
			(clearance 0.0508)
			(thermal_gap 0.0508)
		)
		(pad "A7" thru_hole circle
			(at 11.999976 0 180)
			(size 0.766318 0.766318)
			(drill 0.359918)
			(layers "*.Cu" "*.Mask")
			(remove_unused_layers no)
			(net "PRSNT_SWB_N")
			(clearance 0.0508)
			(thermal_gap 0.0508)
		)
		(pad "A8" thru_hole circle
			(at 13.999972 0.199898 180)
			(size 0.906272 0.906272)
			(drill 0.499872)
			(layers "*.Cu" "*.Mask")
			(remove_unused_layers no)
			(net "GND")
			(clearance 0.0508)
			(thermal_gap 0.0508)
		)
		(pad "B1" thru_hole circle
			(at 0 1.199896 180)
			(size 0.906272 0.906272)
			(drill 0.499872)
			(layers "*.Cu" "*.Mask")
			(remove_unused_layers no)
			(net "GND")
			(clearance 0.0508)
			(thermal_gap 0.0508)
		)
		(pad "B3" thru_hole circle
			(at 3.999992 1.199896 180)
			(size 0.906272 0.906272)
			(drill 0.499872)
			(layers "*.Cu" "*.Mask")
			(remove_unused_layers no)
			(net "GND")
			(clearance 0.0508)
			(thermal_gap 0.0508)
		)
		(pad "B5" thru_hole circle
			(at 7.999984 1.199896 180)
			(size 0.906272 0.906272)
			(drill 0.499872)
			(layers "*.Cu" "*.Mask")
			(remove_unused_layers no)
			(net "GND")
			(clearance 0.0508)
			(thermal_gap 0.0508)
		)
		(pad "B7" thru_hole circle
			(at 11.999976 1.199896 180)
			(size 0.906272 0.906272)
			(drill 0.499872)
			(layers "*.Cu" "*.Mask")
			(remove_unused_layers no)
			(net "GND")
			(clearance 0.0508)
			(thermal_gap 0.0508)
		)
		(pad "D2" thru_hole circle
			(at 1.999996 3.800094 180)
			(size 0.906272 0.906272)
			(drill 0.499872)
			(layers "*.Cu" "*.Mask")
			(remove_unused_layers no)
			(net "GND")
			(clearance 0.0508)
			(thermal_gap 0.0508)
		)
		(pad "D4" thru_hole circle
			(at 5.999988 3.800094 180)
			(size 0.906272 0.906272)
			(drill 0.499872)
			(layers "*.Cu" "*.Mask")
			(remove_unused_layers no)
			(net "GND")
			(clearance 0.0508)
			(thermal_gap 0.0508)
		)
		(pad "D6" thru_hole circle
			(at 9.99998 3.800094 180)
			(size 0.906272 0.906272)
			(drill 0.499872)
			(layers "*.Cu" "*.Mask")
			(remove_unused_layers no)
			(net "GND")
			(clearance 0.0508)
			(thermal_gap 0.0508)
		)
		(pad "D8" thru_hole circle
			(at 13.999972 3.800094 180)
			(size 0.906272 0.906272)
			(drill 0.499872)
			(layers "*.Cu" "*.Mask")
			(remove_unused_layers no)
			(net "GND")
			(clearance 0.0508)
			(thermal_gap 0.0508)
		)
		(pad "E1" thru_hole circle
			(at 0 4.800092 180)
			(size 0.906272 0.906272)
			(drill 0.499872)
			(layers "*.Cu" "*.Mask")
			(remove_unused_layers no)
			(net "GND")
			(clearance 0.0508)
			(thermal_gap 0.0508)
		)
		(pad "E3" thru_hole circle
			(at 3.999992 4.800092 180)
			(size 0.906272 0.906272)
			(drill 0.499872)
			(layers "*.Cu" "*.Mask")
			(remove_unused_layers no)
			(net "GND")
			(clearance 0.0508)
			(thermal_gap 0.0508)
		)
		(pad "E5" thru_hole circle
			(at 7.999984 4.800092 180)
			(size 0.906272 0.906272)
			(drill 0.499872)
			(layers "*.Cu" "*.Mask")
			(remove_unused_layers no)
			(net "GND")
			(clearance 0.0508)
			(thermal_gap 0.0508)
		)
		(pad "E7" thru_hole circle
			(at 11.999976 4.800092 180)
			(size 0.906272 0.906272)
			(drill 0.499872)
			(layers "*.Cu" "*.Mask")
			(remove_unused_layers no)
			(net "GND")
			(clearance 0.0508)
			(thermal_gap 0.0508)
		)
		(pad "G2" thru_hole circle
			(at 1.999996 7.400036 180)
			(size 0.906272 0.906272)
			(drill 0.499872)
			(layers "*.Cu" "*.Mask")
			(remove_unused_layers no)
			(net "GND")
			(clearance 0.0508)
			(thermal_gap 0.0508)
		)
		(pad "G4" thru_hole circle
			(at 5.999988 7.400036 180)
			(size 0.906272 0.906272)
			(drill 0.499872)
			(layers "*.Cu" "*.Mask")
			(remove_unused_layers no)
			(net "GND")
			(clearance 0.0508)
			(thermal_gap 0.0508)
		)
		(pad "G6" thru_hole circle
			(at 9.99998 7.400036 180)
			(size 0.906272 0.906272)
			(drill 0.499872)
			(layers "*.Cu" "*.Mask")
			(remove_unused_layers no)
			(net "GND")
			(clearance 0.0508)
			(thermal_gap 0.0508)
		)
		(pad "G8" thru_hole circle
			(at 13.999972 7.400036 180)
			(size 0.906272 0.906272)
			(drill 0.499872)
			(layers "*.Cu" "*.Mask")
			(remove_unused_layers no)
			(net "GND")
			(clearance 0.0508)
			(thermal_gap 0.0508)
		)
		(pad "H1" thru_hole circle
			(at 0 8.400034 180)
			(size 0.906272 0.906272)
			(drill 0.499872)
			(layers "*.Cu" "*.Mask")
			(remove_unused_layers no)
			(net "GND")
			(clearance 0.0508)
			(thermal_gap 0.0508)
		)
		(pad "H3" thru_hole circle
			(at 3.999992 8.400034 180)
			(size 0.906272 0.906272)
			(drill 0.499872)
			(layers "*.Cu" "*.Mask")
			(remove_unused_layers no)
			(net "GND")
			(clearance 0.0508)
			(thermal_gap 0.0508)
		)
		(pad "H5" thru_hole circle
			(at 7.999984 8.400034 180)
			(size 0.906272 0.906272)
			(drill 0.499872)
			(layers "*.Cu" "*.Mask")
			(remove_unused_layers no)
			(net "GND")
			(clearance 0.0508)
			(thermal_gap 0.0508)
		)
		(pad "H7" thru_hole circle
			(at 11.999976 8.400034 180)
			(size 0.906272 0.906272)
			(drill 0.499872)
			(layers "*.Cu" "*.Mask")
			(remove_unused_layers no)
			(net "GND")
			(clearance 0.0508)
			(thermal_gap 0.0508)
		)
		(pad "J2" thru_hole circle
			(at 1.999996 10.999978 180)
			(size 0.906272 0.906272)
			(drill 0.499872)
			(layers "*.Cu" "*.Mask")
			(remove_unused_layers no)
			(net "GND")
			(clearance 0.0508)
			(thermal_gap 0.0508)
		)
		(pad "J4" thru_hole circle
			(at 5.999988 10.999978 180)
			(size 0.906272 0.906272)
			(drill 0.499872)
			(layers "*.Cu" "*.Mask")
			(remove_unused_layers no)
			(net "GND")
			(clearance 0.0508)
			(thermal_gap 0.0508)
		)
		(pad "J6" thru_hole circle
			(at 9.99998 10.999978 180)
			(size 0.906272 0.906272)
			(drill 0.499872)
			(layers "*.Cu" "*.Mask")
			(remove_unused_layers no)
			(net "GND")
			(clearance 0.0508)
			(thermal_gap 0.0508)
		)
	)
)
